# SCM (Grand Teton) — schematic netlist excerpt (pin names and nets, part order shuffled) for the footprints in the layout excerpt that follows; sources: Cadence DE-HDL packaged netlist, KiCad conversion of 12092022_DA0F0TMDCD0_F0T_Management_Board_D_brd_V3_OCP.brd

R548  Q_RES  33.2 1% CHIP  pkg 0402LF  page 25 : A = BMC_RSTIND_N ; B = RD_N
R443  Q_RES  33.2 1% CHIP  pkg 0402LF  page 13 : A = SMB_BMC_ALERT4_N ; B = SMB_BMC_ALERT4_R_N

(kicad_pcb
	(version 20260206)
	(generator "pcbnew")
	(generator_version "10.0")
	(general
		(thickness 1.6)
		(legacy_teardrops no)
	)
	(paper "A4")
	(title_block
		(title "12092022_DA0F0TMDCD0_F0T_Management_Board_D_brd_V3_OCP.brd")
		(comment 1 "Grand Teton / footprints 262-263 of 1440")
	)
	(layers
		(0 "F.Cu" signal "TOP")
		(4 "In1.Cu" signal "GND")
		(6 "In2.Cu" signal "IN1")
		(8 "In3.Cu" signal "GND1")
		(10 "In4.Cu" signal "IN2")
		(12 "In5.Cu" signal "VCC")
		(14 "In6.Cu" signal "VCC1")
		(16 "In7.Cu" signal "IN3")
		(18 "In8.Cu" signal "GND2")
		(20 "In9.Cu" signal "IN4")
		(22 "In10.Cu" signal "GND3")
		(2 "B.Cu" signal "BOTTOM")
		(9 "F.Adhes" user "F.Adhesive")
		(11 "B.Adhes" user "B.Adhesive")
		(13 "F.Paste" user "Package Geometry/Pastemask Top")
		(15 "B.Paste" user "Package Geometry/Pastemask Bottom")
		(5 "F.SilkS" user "Ref Des/Silkscreen Top")
		(7 "B.SilkS" user "Ref Des/Silkscreen Bottom")
		(1 "F.Mask" user "Board Geometry/Soldermask Top")
		(3 "B.Mask" user "Board Geometry/Soldermask Bottom")
		(17 "Dwgs.User" user "User.Drawings")
		(19 "Cmts.User" user "User.Comments")
		(21 "Eco1.User" user "User.Eco1")
		(23 "Eco2.User" user "User.Eco2")
		(25 "Edge.Cuts" user "Board Geometry/Outline")
		(27 "Margin" user)
		(31 "F.CrtYd" user "Package Geometry/Place Bound Top")
		(29 "B.CrtYd" user "Package Geometry/Place Bound Bottom")
		(35 "F.Fab" user "Ref Des/Assembly Top")
		(33 "B.Fab" user "Ref Des/Assembly Bottom")
	)
	(footprint ""
		(layer "F.Cu")
		(at 46.9646 -77.2668)
		(property "Reference" "R548"
			(at 0 0 0)
			(layer "F.SilkS")
			(hide yes)
			(effects
				(font
					(size 1.27 1.27)
				)
			)
		)
		(property "Value" ""
			(at 0 0 0)
			(layer "F.Fab")
			(effects
				(font
					(size 1.27 1.27)
				)
			)
		)
		(duplicate_pad_numbers_are_jumpers no)
		(fp_line
			(start -0.7874 -0.4064)
			(end 0.7874 -0.4064)
			(stroke
				(width 0.1524)
				(type default)
			)
			(layer "F.SilkS")
		)
		(fp_line
			(start -0.7874 0.4064)
			(end -0.7874 -0.4064)
			(stroke
				(width 0.1524)
				(type default)
			)
			(layer "F.SilkS")
		)
		(fp_line
			(start 0.7874 -0.4064)
			(end 0.7874 0.4064)
			(stroke
				(width 0.1524)
				(type default)
			)
			(layer "F.SilkS")
		)
		(fp_line
			(start 0.7874 0.4064)
			(end -0.7874 0.4064)
			(stroke
				(width 0.1524)
				(type default)
			)
			(layer "F.SilkS")
		)
		(fp_line
			(start -0.67945 -0.305054)
			(end -0.12065 -0.305054)
			(stroke
				(width 0.1)
				(type default)
			)
			(layer "F.Fab")
		)
		(fp_line
			(start -0.67945 0.3048)
			(end -0.67945 -0.305054)
			(stroke
				(width 0.1)
				(type default)
			)
			(layer "F.Fab")
		)
		(fp_line
			(start -0.12065 -0.305054)
			(end -0.12065 -0.2794)
			(stroke
				(width 0.1)
				(type default)
			)
			(layer "F.Fab")
		)
		(fp_line
			(start -0.12065 -0.2794)
			(end 0.12065 -0.2794)
			(stroke
				(width 0.1)
				(type default)
			)
			(layer "F.Fab")
		)
		(fp_line
			(start -0.12065 0.2794)
			(end -0.12065 0.3048)
			(stroke
				(width 0.1)
				(type default)
			)
			(layer "F.Fab")
		)
		(fp_line
			(start -0.12065 0.3048)
			(end -0.67945 0.3048)
			(stroke
				(width 0.1)
				(type default)
			)
			(layer "F.Fab")
		)
		(fp_line
			(start 0.120396 0.2794)
			(end -0.12065 0.2794)
			(stroke
				(width 0.1)
				(type default)
			)
			(layer "F.Fab")
		)
		(fp_line
			(start 0.120396 0.3048)
			(end 0.120396 0.2794)
			(stroke
				(width 0.1)
				(type default)
			)
			(layer "F.Fab")
		)
		(fp_line
			(start 0.12065 -0.3048)
			(end 0.67945 -0.3048)
			(stroke
				(width 0.1)
				(type default)
			)
			(layer "F.Fab")
		)
		(fp_line
			(start 0.12065 -0.2794)
			(end 0.12065 -0.3048)
			(stroke
				(width 0.1)
				(type default)
			)
			(layer "F.Fab")
		)
		(fp_line
			(start 0.67945 -0.3048)
			(end 0.67945 0.3048)
			(stroke
				(width 0.1)
				(type default)
			)
			(layer "F.Fab")
		)
		(fp_line
			(start 0.67945 0.3048)
			(end 0.120396 0.3048)
			(stroke
				(width 0.1)
				(type default)
			)
			(layer "F.Fab")
		)
		(pad "1" smd circle
			(at -0.40005 0)
			(size 0 0)
			(layers "F.Cu" "F.Mask" "F.Paste")
			(net "BMC_RSTIND_N")
		)
		(pad "2" smd circle
			(at 0.40005 0)
			(size 0 0)
			(layers "F.Cu" "F.Mask" "F.Paste")
			(net "RD_N")
		)
	)
	(footprint ""
		(layer "F.Cu")
		(at 40.0558 -42.4434)
		(property "Reference" "R443"
			(at 0 0 0)
			(layer "F.SilkS")
			(hide yes)
			(effects
				(font
					(size 1.27 1.27)
				)
			)
		)
		(property "Value" ""
			(at 0 0 0)
			(layer "F.Fab")
			(effects
				(font
					(size 1.27 1.27)
				)
			)
		)
		(duplicate_pad_numbers_are_jumpers no)
		(fp_line
			(start -0.7874 -0.4064)
			(end 0.7874 -0.4064)
			(stroke
				(width 0.1524)
				(type default)
			)
			(layer "F.SilkS")
		)
		(fp_line
			(start -0.7874 0.4064)
			(end -0.7874 -0.4064)
			(stroke
				(width 0.1524)
				(type default)
			)
			(layer "F.SilkS")
		)
		(fp_line
			(start 0.7874 -0.4064)
			(end 0.7874 0.4064)
			(stroke
				(width 0.1524)
				(type default)
			)
			(layer "F.SilkS")
		)
		(fp_line
			(start 0.7874 0.4064)
			(end -0.7874 0.4064)
			(stroke
				(width 0.1524)
				(type default)
			)
			(layer "F.SilkS")
		)
		(fp_line
			(start -0.67945 -0.305054)
			(end -0.12065 -0.305054)
			(stroke
				(width 0.1)
				(type default)
			)
			(layer "F.Fab")
		)
		(fp_line
			(start -0.67945 0.3048)
			(end -0.67945 -0.305054)
			(stroke
				(width 0.1)
				(type default)
			)
			(layer "F.Fab")
		)
		(fp_line
			(start -0.12065 -0.305054)
			(end -0.12065 -0.2794)
			(stroke
				(width 0.1)
				(type default)
			)
			(layer "F.Fab")
		)
		(fp_line
			(start -0.12065 -0.2794)
			(end 0.12065 -0.2794)
			(stroke
				(width 0.1)
				(type default)
			)
			(layer "F.Fab")
		)
		(fp_line
			(start -0.12065 0.2794)
			(end -0.12065 0.3048)
			(stroke
				(width 0.1)
				(type default)
			)
			(layer "F.Fab")
		)
		(fp_line
			(start -0.12065 0.3048)
			(end -0.67945 0.3048)
			(stroke
				(width 0.1)
				(type default)
			)
			(layer "F.Fab")
		)
		(fp_line
			(start 0.120396 0.2794)
			(end -0.12065 0.2794)
			(stroke
				(width 0.1)
				(type default)
			)
			(layer "F.Fab")
		)
		(fp_line
			(start 0.120396 0.3048)
			(end 0.120396 0.2794)
			(stroke
				(width 0.1)
				(type default)
			)
			(layer "F.Fab")
		)
		(fp_line
			(start 0.12065 -0.3048)
			(end 0.67945 -0.3048)
			(stroke
				(width 0.1)
				(type default)
			)
			(layer "F.Fab")
		)
		(fp_line
			(start 0.12065 -0.2794)
			(end 0.12065 -0.3048)
			(stroke
				(width 0.1)
				(type default)
			)
			(layer "F.Fab")
		)
		(fp_line
			(start 0.67945 -0.3048)
			(end 0.67945 0.3048)
			(stroke
				(width 0.1)
				(type default)
			)
			(layer "F.Fab")
		)
		(fp_line
			(start 0.67945 0.3048)
			(end 0.120396 0.3048)
			(stroke
				(width 0.1)
				(type default)
			)
			(layer "F.Fab")
		)
		(pad "1" smd circle
			(at -0.40005 0)
			(size 0 0)
			(layers "F.Cu" "F.Mask" "F.Paste")
			(net "SMB_BMC_ALERT4_N")
		)
		(pad "2" smd circle
			(at 0.40005 0)
			(size 0 0)
			(layers "F.Cu" "F.Mask" "F.Paste")
			(net "SMB_BMC_ALERT4_R_N")
		)
	)
)
